# SCM (Grand Teton) — schematic netlist excerpt (pin names and nets, part order shuffled) for the footprints in the layout excerpt that follows; sources: Cadence DE-HDL packaged netlist, KiCad conversion of 12092022_DA0F0TMDCD0_F0T_Management_Board_D_brd_V3_OCP.brd

R389  Q_RES  316 1% CHIP  pkg 0402LF  page 50 : A = LED_D21_R1 ; B = P12V_AUX
R336  Q_RES  120 1% CHIP  pkg 0402LF  page 20 : A = GND ; B = M_BMC_DDR4_MA<10>

(kicad_pcb
	(version 20260206)
	(generator "pcbnew")
	(generator_version "10.0")
	(general
		(thickness 1.6)
		(legacy_teardrops no)
	)
	(paper "A4")
	(title_block
		(title "12092022_DA0F0TMDCD0_F0T_Management_Board_D_brd_V3_OCP.brd")
		(comment 1 "Grand Teton / footprints 202-203 of 1440")
	)
	(layers
		(0 "F.Cu" signal "TOP")
		(4 "In1.Cu" signal "GND")
		(6 "In2.Cu" signal "IN1")
		(8 "In3.Cu" signal "GND1")
		(10 "In4.Cu" signal "IN2")
		(12 "In5.Cu" signal "VCC")
		(14 "In6.Cu" signal "VCC1")
		(16 "In7.Cu" signal "IN3")
		(18 "In8.Cu" signal "GND2")
		(20 "In9.Cu" signal "IN4")
		(22 "In10.Cu" signal "GND3")
		(2 "B.Cu" signal "BOTTOM")
		(9 "F.Adhes" user "F.Adhesive")
		(11 "B.Adhes" user "B.Adhesive")
		(13 "F.Paste" user "Package Geometry/Pastemask Top")
		(15 "B.Paste" user "Package Geometry/Pastemask Bottom")
		(5 "F.SilkS" user "Ref Des/Silkscreen Top")
		(7 "B.SilkS" user "Ref Des/Silkscreen Bottom")
		(1 "F.Mask" user "Board Geometry/Soldermask Top")
		(3 "B.Mask" user "Board Geometry/Soldermask Bottom")
		(17 "Dwgs.User" user "User.Drawings")
		(19 "Cmts.User" user "User.Comments")
		(21 "Eco1.User" user "User.Eco1")
		(23 "Eco2.User" user "User.Eco2")
		(25 "Edge.Cuts" user "Board Geometry/Outline")
		(27 "Margin" user)
		(31 "F.CrtYd" user "Package Geometry/Place Bound Top")
		(29 "B.CrtYd" user "Package Geometry/Place Bound Bottom")
		(35 "F.Fab" user "Ref Des/Assembly Top")
		(33 "B.Fab" user "Ref Des/Assembly Bottom")
	)
	(footprint ""
		(layer "F.Cu")
		(at 78.723744 -35.527488 90)
		(property "Reference" "R336"
			(at 0 0 90)
			(layer "F.SilkS")
			(hide yes)
			(effects
				(font
					(size 1.27 1.27)
				)
			)
		)
		(property "Value" ""
			(at 0 0 90)
			(layer "F.Fab")
			(effects
				(font
					(size 1.27 1.27)
				)
			)
		)
		(duplicate_pad_numbers_are_jumpers no)
		(fp_line
			(start 0.7874 -0.4064)
			(end 0.7874 0.4064)
			(stroke
				(width 0.1524)
				(type default)
			)
			(layer "F.SilkS")
		)
		(fp_line
			(start -0.7874 -0.4064)
			(end 0.7874 -0.4064)
			(stroke
				(width 0.1524)
				(type default)
			)
			(layer "F.SilkS")
		)
		(fp_line
			(start 0.7874 0.4064)
			(end -0.7874 0.4064)
			(stroke
				(width 0.1524)
				(type default)
			)
			(layer "F.SilkS")
		)
		(fp_line
			(start -0.7874 0.4064)
			(end -0.7874 -0.4064)
			(stroke
				(width 0.1524)
				(type default)
			)
			(layer "F.SilkS")
		)
		(fp_line
			(start -0.12065 -0.305054)
			(end -0.12065 -0.2794)
			(stroke
				(width 0.1)
				(type default)
			)
			(layer "F.Fab")
		)
		(fp_line
			(start -0.67945 -0.305054)
			(end -0.12065 -0.305054)
			(stroke
				(width 0.1)
				(type default)
			)
			(layer "F.Fab")
		)
		(fp_line
			(start 0.67945 -0.3048)
			(end 0.67945 0.3048)
			(stroke
				(width 0.1)
				(type default)
			)
			(layer "F.Fab")
		)
		(fp_line
			(start 0.12065 -0.3048)
			(end 0.67945 -0.3048)
			(stroke
				(width 0.1)
				(type default)
			)
			(layer "F.Fab")
		)
		(fp_line
			(start 0.12065 -0.2794)
			(end 0.12065 -0.3048)
			(stroke
				(width 0.1)
				(type default)
			)
			(layer "F.Fab")
		)
		(fp_line
			(start -0.12065 -0.2794)
			(end 0.12065 -0.2794)
			(stroke
				(width 0.1)
				(type default)
			)
			(layer "F.Fab")
		)
		(fp_line
			(start 0.120396 0.2794)
			(end -0.12065 0.2794)
			(stroke
				(width 0.1)
				(type default)
			)
			(layer "F.Fab")
		)
		(fp_line
			(start -0.12065 0.2794)
			(end -0.12065 0.3048)
			(stroke
				(width 0.1)
				(type default)
			)
			(layer "F.Fab")
		)
		(fp_line
			(start 0.67945 0.3048)
			(end 0.120396 0.3048)
			(stroke
				(width 0.1)
				(type default)
			)
			(layer "F.Fab")
		)
		(fp_line
			(start 0.120396 0.3048)
			(end 0.120396 0.2794)
			(stroke
				(width 0.1)
				(type default)
			)
			(layer "F.Fab")
		)
		(fp_line
			(start -0.12065 0.3048)
			(end -0.67945 0.3048)
			(stroke
				(width 0.1)
				(type default)
			)
			(layer "F.Fab")
		)
		(fp_line
			(start -0.67945 0.3048)
			(end -0.67945 -0.305054)
			(stroke
				(width 0.1)
				(type default)
			)
			(layer "F.Fab")
		)
		(pad "1" smd circle
			(at -0.40005 0 90)
			(size 0 0)
			(layers "F.Cu" "F.Mask" "F.Paste")
			(net "GND")
		)
		(pad "2" smd circle
			(at 0.40005 0 90)
			(size 0 0)
			(layers "F.Cu" "F.Mask" "F.Paste")
			(net "M_BMC_DDR4_MA<10>")
		)
	)
	(footprint ""
		(layer "F.Cu")
		(at 55.626 -10.795 90)
		(property "Reference" "R389"
			(at 0 0 90)
			(layer "F.SilkS")
			(hide yes)
			(effects
				(font
					(size 1.27 1.27)
				)
			)
		)
		(property "Value" ""
			(at 0 0 90)
			(layer "F.Fab")
			(effects
				(font
					(size 1.27 1.27)
				)
			)
		)
		(duplicate_pad_numbers_are_jumpers no)
		(fp_line
			(start 0.7874 -0.4064)
			(end 0.7874 0.4064)
			(stroke
				(width 0.1524)
				(type default)
			)
			(layer "F.SilkS")
		)
		(fp_line
			(start -0.7874 -0.4064)
			(end 0.7874 -0.4064)
			(stroke
				(width 0.1524)
				(type default)
			)
			(layer "F.SilkS")
		)
		(fp_line
			(start 0.7874 0.4064)
			(end -0.7874 0.4064)
			(stroke
				(width 0.1524)
				(type default)
			)
			(layer "F.SilkS")
		)
		(fp_line
			(start -0.7874 0.4064)
			(end -0.7874 -0.4064)
			(stroke
				(width 0.1524)
				(type default)
			)
			(layer "F.SilkS")
		)
		(fp_line
			(start -0.12065 -0.305054)
			(end -0.12065 -0.2794)
			(stroke
				(width 0.1)
				(type default)
			)
			(layer "F.Fab")
		)
		(fp_line
			(start -0.67945 -0.305054)
			(end -0.12065 -0.305054)
			(stroke
				(width 0.1)
				(type default)
			)
			(layer "F.Fab")
		)
		(fp_line
			(start 0.67945 -0.3048)
			(end 0.67945 0.3048)
			(stroke
				(width 0.1)
				(type default)
			)
			(layer "F.Fab")
		)
		(fp_line
			(start 0.12065 -0.3048)
			(end 0.67945 -0.3048)
			(stroke
				(width 0.1)
				(type default)
			)
			(layer "F.Fab")
		)
		(fp_line
			(start 0.12065 -0.2794)
			(end 0.12065 -0.3048)
			(stroke
				(width 0.1)
				(type default)
			)
			(layer "F.Fab")
		)
		(fp_line
			(start -0.12065 -0.2794)
			(end 0.12065 -0.2794)
			(stroke
				(width 0.1)
				(type default)
			)
			(layer "F.Fab")
		)
		(fp_line
			(start 0.120396 0.2794)
			(end -0.12065 0.2794)
			(stroke
				(width 0.1)
				(type default)
			)
			(layer "F.Fab")
		)
		(fp_line
			(start -0.12065 0.2794)
			(end -0.12065 0.3048)
			(stroke
				(width 0.1)
				(type default)
			)
			(layer "F.Fab")
		)
		(fp_line
			(start 0.67945 0.3048)
			(end 0.120396 0.3048)
			(stroke
				(width 0.1)
				(type default)
			)
			(layer "F.Fab")
		)
		(fp_line
			(start 0.120396 0.3048)
			(end 0.120396 0.2794)
			(stroke
				(width 0.1)
				(type default)
			)
			(layer "F.Fab")
		)
		(fp_line
			(start -0.12065 0.3048)
			(end -0.67945 0.3048)
			(stroke
				(width 0.1)
				(type default)
			)
			(layer "F.Fab")
		)
		(fp_line
			(start -0.67945 0.3048)
			(end -0.67945 -0.305054)
			(stroke
				(width 0.1)
				(type default)
			)
			(layer "F.Fab")
		)
		(pad "1" smd circle
			(at -0.40005 0 90)
			(size 0 0)
			(layers "F.Cu" "F.Mask" "F.Paste")
			(net "LED_D21_R1")
		)
		(pad "2" smd circle
			(at 0.40005 0 90)
			(size 0 0)
			(layers "F.Cu" "F.Mask" "F.Paste")
			(net "P12V_AUX")
		)
	)
)
